# TIMECARD (Time Appliance Project (Time Card)) — schematic netlist excerpt (pin names and nets, part order shuffled) for the footprints in the layout excerpt that follows; sources: Cadence DE-HDL packaged netlist, KiCad conversion of R4006-B0001-02_R01.brd

DS9  OPTICAL  pkg SMC_DS_063X031_V4  page 26 : A = UNNAMED_14_OPTICAL_I292_A ; C = SG
SP54  NULL  pkg DUMMY  page 34
TP19  TP_PIONT  pkg TP010CT020B030_PTH  page 25 : \1\ = SN_EEPROM_WP

(kicad_pcb
	(version 20260206)
	(generator "pcbnew")
	(generator_version "10.0")
	(general
		(thickness 1.6)
		(legacy_teardrops no)
	)
	(paper "A4")
	(title_block
		(title "timecard-production-celestica-r4006 — R4006-B0001-02_R01.brd")
		(comment 1 "Time Appliance Project (Time Card) / footprints 401-403 of 1113")
	)
	(layers
		(0 "F.Cu" signal "TOP")
		(4 "In1.Cu" signal "L02_GND1")
		(6 "In2.Cu" signal "L03_SIG1")
		(8 "In3.Cu" signal "L04_GND2")
		(10 "In4.Cu" signal "L05_VCC1")
		(12 "In5.Cu" signal "L06_VCC2")
		(14 "In6.Cu" signal "L07_GND3")
		(16 "In7.Cu" signal "L08_SIG2")
		(18 "In8.Cu" signal "L09_GND4")
		(2 "B.Cu" signal "BOTTOM")
		(9 "F.Adhes" user "F.Adhesive")
		(11 "B.Adhes" user "B.Adhesive")
		(13 "F.Paste" user "Package Geometry/Pastemask Top")
		(15 "B.Paste" user "Package Geometry/Pastemask Bottom")
		(5 "F.SilkS" user "Ref Des/Silkscreen Top")
		(7 "B.SilkS" user "Ref Des/Silkscreen Bottom")
		(1 "F.Mask" user "Board Geometry/Soldermask Top")
		(3 "B.Mask" user "Board Geometry/Soldermask Bottom")
		(17 "Dwgs.User" user "User.Drawings")
		(19 "Cmts.User" user "User.Comments")
		(21 "Eco1.User" user "User.Eco1")
		(23 "Eco2.User" user "User.Eco2")
		(25 "Edge.Cuts" user "Board Geometry/Outline")
		(27 "Margin" user)
		(31 "F.CrtYd" user "Package Geometry/Place Bound Top")
		(29 "B.CrtYd" user "Package Geometry/Place Bound Bottom")
		(35 "F.Fab" user "Ref Des/Assembly Top")
		(33 "B.Fab" user "Ref Des/Assembly Bottom")
	)
	(footprint ""
		(layer "F.Cu")
		(at 87.503 -67.31)
		(property "Reference" "TP19"
			(at -0.7874 -0.85725 0)
			(unlocked yes)
			(layer "F.SilkS")
			(effects
				(font
					(size 0.635 0.4064)
					(thickness 0.1524)
				)
				(justify left)
			)
		)
		(property "Value" ""
			(at 0 0 0)
			(layer "F.Fab")
			(effects
				(font
					(size 1.27 1.27)
				)
			)
		)
		(property "Device Type" "TP_PIONT-TP010CT020B030_PTH-TPA"
			(at -1.341882 0.996696 0)
			(unlocked yes)
			(layer "F.Fab")
			(hide yes)
			(effects
				(font
					(size 0.7874 0.5842)
					(thickness 0.000001)
				)
				(justify left)
			)
		)
		(duplicate_pad_numbers_are_jumpers no)
		(fp_poly
			(pts
				(arc
					(start 0.889 0)
					(mid -0.889 0)
					(end 0.889 0)
				)
			)
			(stroke
				(width 0)
				(type default)
			)
			(fill no)
			(layer "B.CrtYd")
		)
		(fp_poly
			(pts
				(arc
					(start 0.889 0)
					(mid -0.889 0)
					(end 0.889 0)
				)
			)
			(stroke
				(width 0)
				(type default)
			)
			(fill no)
			(layer "F.CrtYd")
		)
		(pad "1" thru_hole circle
			(at 0 0)
			(size 0.508 0.508)
			(drill 0.254)
			(layers "*.Cu" "*.Mask")
			(remove_unused_layers no)
			(net "SN_EEPROM_WP")
			(clearance 0.1016)
			(padstack
				(mode front_inner_back)
				(layer "Inner"
					(shape circle)
					(size 0.508 0.508)
					(clearance 0.1016)
				)
				(layer "B.Cu"
					(shape circle)
					(size 0.762 0.762)
					(clearance -0.0254)
				)
			)
		)
	)
	(footprint ""
		(layer "F.Cu")
		(at 134.1882 -106.172254 -90)
		(property "Reference" "DS9"
			(at -0.126746 2.19583 90)
			(unlocked yes)
			(layer "F.SilkS")
			(effects
				(font
					(size 0.7874 0.5842)
					(thickness 0.1524)
				)
			)
		)
		(property "Value" ""
			(at 0 0 270)
			(layer "F.Fab")
			(effects
				(font
					(size 1.27 1.27)
				)
			)
		)
		(property "User Part Number" "PARTNUM*"
			(at 0.1778 2.422881 270)
			(unlocked yes)
			(layer "Cmts.User")
			(hide yes)
			(effects
				(font
					(size 0.786892 0.583946)
					(thickness 0.000001)
				)
			)
		)
		(property "Device Type" "OPTICAL-G170-10143-01"
			(at 0.1778 1.483081 270)
			(unlocked yes)
			(layer "F.Fab")
			(hide yes)
			(effects
				(font
					(size 0.786892 0.583946)
					(thickness 0.000001)
				)
			)
		)
		(duplicate_pad_numbers_are_jumpers no)
		(fp_line
			(start -1.3208 1.3462)
			(end -2.5908 1.3462)
			(stroke
				(width 0.1)
				(type default)
			)
			(layer "F.SilkS")
		)
		(fp_line
			(start -1.9558 0.7112)
			(end -1.9558 1.9812)
			(stroke
				(width 0.1)
				(type default)
			)
			(layer "F.SilkS")
		)
		(fp_line
			(start -1.397508 0.704088)
			(end -1.397508 -0.704088)
			(stroke
				(width 0.1)
				(type default)
			)
			(layer "F.SilkS")
		)
		(fp_line
			(start 1.397508 0.704088)
			(end -1.397508 0.704088)
			(stroke
				(width 0.1)
				(type default)
			)
			(layer "F.SilkS")
		)
		(fp_line
			(start -1.397508 -0.704088)
			(end 1.397508 -0.704088)
			(stroke
				(width 0.1)
				(type default)
			)
			(layer "F.SilkS")
		)
		(fp_line
			(start 1.397508 -0.704088)
			(end 1.397508 0.704088)
			(stroke
				(width 0.1)
				(type default)
			)
			(layer "F.SilkS")
		)
		(fp_rect
			(start 1.905508 0.704088)
			(end 1.397508 -0.704088)
			(stroke
				(width 0)
				(type default)
			)
			(fill yes)
			(layer "F.SilkS")
		)
		(fp_rect
			(start 1.905508 0.958088)
			(end -1.651508 -0.958088)
			(stroke
				(width 0)
				(type default)
			)
			(fill no)
			(layer "F.CrtYd")
		)
		(fp_line
			(start -0.850138 0.450088)
			(end 0.850138 0.450088)
			(stroke
				(width 0.1)
				(type default)
			)
			(layer "F.Fab")
		)
		(fp_line
			(start 0.850138 0.450088)
			(end 0.850138 -0.450088)
			(stroke
				(width 0.1)
				(type default)
			)
			(layer "F.Fab")
		)
		(fp_line
			(start -2.2098 0.0762)
			(end -3.4798 0.0762)
			(stroke
				(width 0.1)
				(type default)
			)
			(layer "F.Fab")
		)
		(fp_line
			(start -0.850138 -0.450088)
			(end -0.850138 0.450088)
			(stroke
				(width 0.1)
				(type default)
			)
			(layer "F.Fab")
		)
		(fp_line
			(start 0.850138 -0.450088)
			(end -0.850138 -0.450088)
			(stroke
				(width 0.1)
				(type default)
			)
			(layer "F.Fab")
		)
		(fp_line
			(start -2.8448 -0.5588)
			(end -2.8448 0.7112)
			(stroke
				(width 0.1)
				(type default)
			)
			(layer "F.Fab")
		)
		(fp_rect
			(start 0.850138 0.450088)
			(end 0.342138 -0.450088)
			(stroke
				(width 0)
				(type default)
			)
			(fill yes)
			(layer "F.Fab")
		)
		(fp_text user "C"
			(at 2.013204 1.4732 0)
			(unlocked yes)
			(layer "F.SilkS")
			(effects
				(font
					(size 0.635 0.4064)
					(thickness 0.1524)
				)
			)
		)
		(fp_text user "A"
			(at -2.126996 0.2032 0)
			(unlocked yes)
			(layer "F.SilkS")
			(effects
				(font
					(size 0.635 0.4064)
					(thickness 0.1524)
				)
			)
		)
		(fp_text user "A"
			(at -1.497076 0.0762 0)
			(unlocked yes)
			(layer "F.Fab")
			(effects
				(font
					(size 0.7874 0.5842)
					(thickness 0.1524)
				)
			)
		)
		(fp_text user "C"
			(at 1.677924 0.0762 0)
			(unlocked yes)
			(layer "F.Fab")
			(effects
				(font
					(size 0.7874 0.5842)
					(thickness 0.1524)
				)
			)
		)
		(pad "A" smd rect
			(at -0.749808 0 270)
			(size 0.7874 0.7874)
			(layers "F.Cu" "F.Mask" "F.Paste")
			(net "UNNAMED_14_OPTICAL_I292_A")
		)
		(pad "C" smd rect
			(at 0.749808 0 270)
			(size 0.7874 0.7874)
			(layers "F.Cu" "F.Mask" "F.Paste")
			(net "SG")
		)
	)
	(footprint ""
		(layer "F.Cu")
		(at 50.165 -126.873)
		(property "Reference" "SP54"
			(at 0 0 0)
			(layer "F.SilkS")
			(hide yes)
			(effects
				(font
					(size 1.27 1.27)
				)
			)
		)
		(property "Value" ""
			(at 0 0 0)
			(layer "F.Fab")
			(effects
				(font
					(size 1.27 1.27)
				)
			)
		)
		(duplicate_pad_numbers_are_jumpers no)
	)
)
